(kicad_pcb
	(version 20260206)
	(generator "pcbnew")
	(generator_version "10.0")
	(general
		(thickness 1.6)
		(legacy_teardrops no)
	)
	(paper "A4")
	(title_block
		(title "v1-chassis-manager — T6M_CM_d_v01_1031_1645.brd")
		(comment 1 "Open CloudServer (Microsoft) / footprints 2174-2183 of 2512")
	)
	(layers
		(0 "F.Cu" signal "TOP")
		(4 "In1.Cu" signal "GND1")
		(6 "In2.Cu" signal "IN1")
		(8 "In3.Cu" signal "VCC1")
		(10 "In4.Cu" signal "VCC2")
		(12 "In5.Cu" signal "GND2")
		(14 "In6.Cu" signal "IN2")
		(16 "In7.Cu" signal "IN3")
		(18 "In8.Cu" signal "GND3")
		(2 "B.Cu" signal "BOTTOM")
		(9 "F.Adhes" user "F.Adhesive")
		(11 "B.Adhes" user "B.Adhesive")
		(13 "F.Paste" user "Package Geometry/Pastemask Top")
		(15 "B.Paste" user "Package Geometry/Pastemask Bottom")
		(5 "F.SilkS" user "Ref Des/Silkscreen Top")
		(7 "B.SilkS" user "Ref Des/Silkscreen Bottom")
		(1 "F.Mask" user "Board Geometry/Soldermask Top")
		(3 "B.Mask" user "Board Geometry/Soldermask Bottom")
		(17 "Dwgs.User" user "User.Drawings")
		(19 "Cmts.User" user "User.Comments")
		(21 "Eco1.User" user "User.Eco1")
		(23 "Eco2.User" user "User.Eco2")
		(25 "Edge.Cuts" user "Board Geometry/Outline")
		(27 "Margin" user)
		(31 "F.CrtYd" user "Package Geometry/Place Bound Top")
		(29 "B.CrtYd" user "Package Geometry/Place Bound Bottom")
		(35 "F.Fab" user "Ref Des/Assembly Top")
		(33 "B.Fab" user "Ref Des/Assembly Bottom")
	)
	(footprint ""
		(layer "B.Cu")
		(at 90.81262 -161.830512)
		(property "Reference" "R912"
			(at 24.774144 20.104354 0)
			(unlocked yes)
			(layer "B.SilkS")
			(effects
				(font
					(size 0.7874 0.5842)
					(thickness 0.1524)
				)
				(justify left mirror)
			)
		)
		(property "Value" ""
			(at 0 0 0)
			(layer "B.Fab")
			(effects
				(font
					(size 1.27 1.27)
				)
				(justify mirror)
			)
		)
		(duplicate_pad_numbers_are_jumpers no)
		(fp_line
			(start -0.7874 -0.4064)
			(end -0.7874 0.4064)
			(stroke
				(width 0.1524)
				(type default)
			)
			(layer "B.SilkS")
		)
		(fp_line
			(start -0.7874 0.4064)
			(end 0.7874 0.4064)
			(stroke
				(width 0.1524)
				(type default)
			)
			(layer "B.SilkS")
		)
		(fp_line
			(start 0.7874 -0.4064)
			(end -0.7874 -0.4064)
			(stroke
				(width 0.1524)
				(type default)
			)
			(layer "B.SilkS")
		)
		(fp_line
			(start 0.7874 0.4064)
			(end 0.7874 -0.4064)
			(stroke
				(width 0.1524)
				(type default)
			)
			(layer "B.SilkS")
		)
		(fp_poly
			(pts
				(xy 0.508 0.2794) (xy 0.508 0.2286) (xy 0.635 0.2286) (xy 0.635 -0.254) (xy 0.5334 -0.254) (xy 0.5334 -0.2794)
				(xy -0.5334 -0.2794) (xy -0.5334 -0.254) (xy -0.635 -0.254) (xy -0.635 0.254) (xy -0.5334 0.254)
				(xy -0.5334 0.2794)
			)
			(stroke
				(width 0)
				(type default)
			)
			(fill no)
			(layer "B.CrtYd")
		)
		(pad "1" smd rect
			(at -0.40005 0 180)
			(size 0.4572 0.508)
			(layers "B.Cu" "B.Mask" "B.Paste")
			(net "UART_T5_NODE1_TXD")
		)
		(pad "2" smd rect
			(at 0.40005 0 180)
			(size 0.4572 0.508)
			(layers "B.Cu" "B.Mask" "B.Paste")
			(net "UART_T5_NODE1_TXD_R")
		)
	)
	(footprint ""
		(layer "B.Cu")
		(at 90.81262 -174.022512)
		(property "Reference" "R703"
			(at 24.902414 20.163028 0)
			(unlocked yes)
			(layer "B.SilkS")
			(effects
				(font
					(size 0.7874 0.5842)
					(thickness 0.1524)
				)
				(justify left mirror)
			)
		)
		(property "Value" ""
			(at 0 0 0)
			(layer "B.Fab")
			(effects
				(font
					(size 1.27 1.27)
				)
				(justify mirror)
			)
		)
		(duplicate_pad_numbers_are_jumpers no)
		(fp_line
			(start -0.7874 -0.4064)
			(end -0.7874 0.4064)
			(stroke
				(width 0.1524)
				(type default)
			)
			(layer "B.SilkS")
		)
		(fp_line
			(start -0.7874 0.4064)
			(end 0.7874 0.4064)
			(stroke
				(width 0.1524)
				(type default)
			)
			(layer "B.SilkS")
		)
		(fp_line
			(start 0.7874 -0.4064)
			(end -0.7874 -0.4064)
			(stroke
				(width 0.1524)
				(type default)
			)
			(layer "B.SilkS")
		)
		(fp_line
			(start 0.7874 0.4064)
			(end 0.7874 -0.4064)
			(stroke
				(width 0.1524)
				(type default)
			)
			(layer "B.SilkS")
		)
		(fp_poly
			(pts
				(xy 0.508 0.2794) (xy 0.508 0.2286) (xy 0.635 0.2286) (xy 0.635 -0.254) (xy 0.5334 -0.254) (xy 0.5334 -0.2794)
				(xy -0.5334 -0.2794) (xy -0.5334 -0.254) (xy -0.635 -0.254) (xy -0.635 0.254) (xy -0.5334 0.254)
				(xy -0.5334 0.2794)
			)
			(stroke
				(width 0)
				(type default)
			)
			(fill no)
			(layer "B.CrtYd")
		)
		(pad "1" smd rect
			(at -0.40005 0 180)
			(size 0.4572 0.508)
			(layers "B.Cu" "B.Mask" "B.Paste")
			(net "T4_NODE1_EN")
		)
		(pad "2" smd rect
			(at 0.40005 0 180)
			(size 0.4572 0.508)
			(layers "B.Cu" "B.Mask" "B.Paste")
			(net "P5V_NODE1")
		)
	)
	(footprint ""
		(layer "B.Cu")
		(at 55.552086 -129.756662 180)
		(property "Reference" "C267"
			(at 41.609518 -53.368702 0)
			(unlocked yes)
			(layer "B.SilkS")
			(effects
				(font
					(size 0.7874 0.5842)
					(thickness 0.1524)
				)
				(justify left mirror)
			)
		)
		(property "Value" ""
			(at 0 0 0)
			(layer "B.Fab")
			(effects
				(font
					(size 1.27 1.27)
				)
				(justify mirror)
			)
		)
		(duplicate_pad_numbers_are_jumpers no)
		(fp_line
			(start 0.7874 0.4064)
			(end 0.7874 -0.4064)
			(stroke
				(width 0.1524)
				(type default)
			)
			(layer "B.SilkS")
		)
		(fp_line
			(start 0.7874 -0.4064)
			(end -0.7874 -0.4064)
			(stroke
				(width 0.1524)
				(type default)
			)
			(layer "B.SilkS")
		)
		(fp_line
			(start 0 0.381)
			(end 0 -0.381)
			(stroke
				(width 0.1524)
				(type default)
			)
			(layer "B.SilkS")
		)
		(fp_line
			(start -0.7874 0.4064)
			(end 0.7874 0.4064)
			(stroke
				(width 0.1524)
				(type default)
			)
			(layer "B.SilkS")
		)
		(fp_line
			(start -0.7874 -0.4064)
			(end -0.7874 0.4064)
			(stroke
				(width 0.1524)
				(type default)
			)
			(layer "B.SilkS")
		)
		(fp_poly
			(pts
				(xy 0.5334 0.254) (xy 0.635 0.254) (xy 0.635 0.2286) (xy 0.635 -0.254) (xy 0.5334 -0.254) (xy 0.5334 -0.2794)
				(xy -0.5334 -0.2794) (xy -0.5334 -0.254) (xy -0.635 -0.254) (xy -0.635 0.254) (xy -0.5334 0.254)
				(xy -0.5334 0.2794) (xy 0.508 0.2794) (xy 0.5334 0.2794)
			)
			(stroke
				(width 0)
				(type default)
			)
			(fill no)
			(layer "B.CrtYd")
		)
		(pad "1" smd rect
			(at -0.40005 0)
			(size 0.4572 0.508)
			(layers "B.Cu" "B.Mask" "B.Paste")
			(net "BMC_NODE1_MPLLAV33")
		)
		(pad "2" smd rect
			(at 0.40005 0)
			(size 0.4572 0.508)
			(layers "B.Cu" "B.Mask" "B.Paste")
			(net "GND")
		)
	)
	(footprint ""
		(layer "B.Cu")
		(at 69.326252 -136.505188 180)
		(property "Reference" "C282"
			(at 35.998912 -52.704746 0)
			(unlocked yes)
			(layer "B.SilkS")
			(effects
				(font
					(size 0.7874 0.5842)
					(thickness 0.1524)
				)
				(justify left mirror)
			)
		)
		(property "Value" ""
			(at 0 0 0)
			(layer "B.Fab")
			(effects
				(font
					(size 1.27 1.27)
				)
				(justify mirror)
			)
		)
		(duplicate_pad_numbers_are_jumpers no)
		(fp_line
			(start 0.7874 0.4064)
			(end 0.7874 -0.4064)
			(stroke
				(width 0.1524)
				(type default)
			)
			(layer "B.SilkS")
		)
		(fp_line
			(start 0.7874 -0.4064)
			(end -0.7874 -0.4064)
			(stroke
				(width 0.1524)
				(type default)
			)
			(layer "B.SilkS")
		)
		(fp_line
			(start 0 0.381)
			(end 0 -0.381)
			(stroke
				(width 0.1524)
				(type default)
			)
			(layer "B.SilkS")
		)
		(fp_line
			(start -0.7874 0.4064)
			(end 0.7874 0.4064)
			(stroke
				(width 0.1524)
				(type default)
			)
			(layer "B.SilkS")
		)
		(fp_line
			(start -0.7874 -0.4064)
			(end -0.7874 0.4064)
			(stroke
				(width 0.1524)
				(type default)
			)
			(layer "B.SilkS")
		)
		(fp_poly
			(pts
				(xy 0.5334 0.254) (xy 0.635 0.254) (xy 0.635 0.2286) (xy 0.635 -0.254) (xy 0.5334 -0.254) (xy 0.5334 -0.2794)
				(xy -0.5334 -0.2794) (xy -0.5334 -0.254) (xy -0.635 -0.254) (xy -0.635 0.254) (xy -0.5334 0.254)
				(xy -0.5334 0.2794) (xy 0.508 0.2794) (xy 0.5334 0.2794)
			)
			(stroke
				(width 0)
				(type default)
			)
			(fill no)
			(layer "B.CrtYd")
		)
		(pad "1" smd rect
			(at -0.40005 0)
			(size 0.4572 0.508)
			(layers "B.Cu" "B.Mask" "B.Paste")
			(net "P3V3_NODE1")
		)
		(pad "2" smd rect
			(at 0.40005 0)
			(size 0.4572 0.508)
			(layers "B.Cu" "B.Mask" "B.Paste")
			(net "GND")
		)
	)
	(footprint ""
		(layer "B.Cu")
		(at 48.452278 -77.678026 180)
		(property "Reference" "C35"
			(at 14.723618 -31.527242 0)
			(unlocked yes)
			(layer "B.SilkS")
			(effects
				(font
					(size 0.7874 0.5842)
					(thickness 0.1524)
				)
				(justify left mirror)
			)
		)
		(property "Value" ""
			(at 0 0 0)
			(layer "B.Fab")
			(effects
				(font
					(size 1.27 1.27)
				)
				(justify mirror)
			)
		)
		(duplicate_pad_numbers_are_jumpers no)
		(fp_line
			(start 0.7874 0.4064)
			(end 0.7874 -0.4064)
			(stroke
				(width 0.1524)
				(type default)
			)
			(layer "B.SilkS")
		)
		(fp_line
			(start 0.7874 -0.4064)
			(end -0.7874 -0.4064)
			(stroke
				(width 0.1524)
				(type default)
			)
			(layer "B.SilkS")
		)
		(fp_line
			(start 0 0.381)
			(end 0 -0.381)
			(stroke
				(width 0.1524)
				(type default)
			)
			(layer "B.SilkS")
		)
		(fp_line
			(start -0.7874 0.4064)
			(end 0.7874 0.4064)
			(stroke
				(width 0.1524)
				(type default)
			)
			(layer "B.SilkS")
		)
		(fp_line
			(start -0.7874 -0.4064)
			(end -0.7874 0.4064)
			(stroke
				(width 0.1524)
				(type default)
			)
			(layer "B.SilkS")
		)
		(fp_poly
			(pts
				(xy 0.5334 0.254) (xy 0.635 0.254) (xy 0.635 0.2286) (xy 0.635 -0.254) (xy 0.5334 -0.254) (xy 0.5334 -0.2794)
				(xy -0.5334 -0.2794) (xy -0.5334 -0.254) (xy -0.635 -0.254) (xy -0.635 0.254) (xy -0.5334 0.254)
				(xy -0.5334 0.2794) (xy 0.508 0.2794) (xy 0.5334 0.2794)
			)
			(stroke
				(width 0)
				(type default)
			)
			(fill no)
			(layer "B.CrtYd")
		)
		(pad "1" smd rect
			(at -0.40005 0)
			(size 0.4572 0.508)
			(layers "B.Cu" "B.Mask" "B.Paste")
			(net "GND")
		)
		(pad "2" smd rect
			(at 0.40005 0)
			(size 0.4572 0.508)
			(layers "B.Cu" "B.Mask" "B.Paste")
			(net "P1V05_NODE1")
		)
	)
	(footprint ""
		(layer "B.Cu")
		(at 65.598802 -62.857634 -90)
		(property "Reference" "C120"
			(at 5.118862 -0.922782 270)
			(unlocked yes)
			(layer "B.SilkS")
			(effects
				(font
					(size 0.7874 0.5842)
					(thickness 0.1524)
				)
				(justify left mirror)
			)
		)
		(property "Value" ""
			(at 0 0 90)
			(layer "B.Fab")
			(effects
				(font
					(size 1.27 1.27)
				)
				(justify mirror)
			)
		)
		(duplicate_pad_numbers_are_jumpers no)
		(fp_line
			(start -0.7874 0.4064)
			(end 0.7874 0.4064)
			(stroke
				(width 0.1524)
				(type default)
			)
			(layer "B.SilkS")
		)
		(fp_line
			(start 0.7874 0.4064)
			(end 0.7874 -0.4064)
			(stroke
				(width 0.1524)
				(type default)
			)
			(layer "B.SilkS")
		)
		(fp_line
			(start 0 0.381)
			(end 0 -0.381)
			(stroke
				(width 0.1524)
				(type default)
			)
			(layer "B.SilkS")
		)
		(fp_line
			(start -0.7874 -0.4064)
			(end -0.7874 0.4064)
			(stroke
				(width 0.1524)
				(type default)
			)
			(layer "B.SilkS")
		)
		(fp_line
			(start 0.7874 -0.4064)
			(end -0.7874 -0.4064)
			(stroke
				(width 0.1524)
				(type default)
			)
			(layer "B.SilkS")
		)
		(fp_poly
			(pts
				(xy 0.5334 0.254) (xy 0.635 0.254) (xy 0.635 0.2286) (xy 0.635 -0.254) (xy 0.5334 -0.254) (xy 0.5334 -0.2794)
				(xy -0.5334 -0.2794) (xy -0.5334 -0.254) (xy -0.635 -0.254) (xy -0.635 0.254) (xy -0.5334 0.254)
				(xy -0.5334 0.2794) (xy 0.508 0.2794) (xy 0.5334 0.2794)
			)
			(stroke
				(width 0)
				(type default)
			)
			(fill no)
			(layer "B.CrtYd")
		)
		(pad "1" smd rect
			(at -0.40005 0 90)
			(size 0.4572 0.508)
			(layers "B.Cu" "B.Mask" "B.Paste")
			(net "PV_VDDR_NODE1")
		)
		(pad "2" smd rect
			(at 0.40005 0 90)
			(size 0.4572 0.508)
			(layers "B.Cu" "B.Mask" "B.Paste")
			(net "GND")
		)
	)
	(footprint ""
		(layer "B.Cu")
		(at 123.70816 -176.442624)
		(property "Reference" "R725"
			(at -28.598876 31.521146 0)
			(unlocked yes)
			(layer "B.SilkS")
			(effects
				(font
					(size 0.7874 0.5842)
					(thickness 0.1524)
				)
				(justify left mirror)
			)
		)
		(property "Value" ""
			(at 0 0 0)
			(layer "B.Fab")
			(effects
				(font
					(size 1.27 1.27)
				)
				(justify mirror)
			)
		)
		(duplicate_pad_numbers_are_jumpers no)
		(fp_line
			(start -0.7874 -0.4064)
			(end -0.7874 0.4064)
			(stroke
				(width 0.1524)
				(type default)
			)
			(layer "B.SilkS")
		)
		(fp_line
			(start -0.7874 0.4064)
			(end 0.7874 0.4064)
			(stroke
				(width 0.1524)
				(type default)
			)
			(layer "B.SilkS")
		)
		(fp_line
			(start 0.7874 -0.4064)
			(end -0.7874 -0.4064)
			(stroke
				(width 0.1524)
				(type default)
			)
			(layer "B.SilkS")
		)
		(fp_line
			(start 0.7874 0.4064)
			(end 0.7874 -0.4064)
			(stroke
				(width 0.1524)
				(type default)
			)
			(layer "B.SilkS")
		)
		(fp_poly
			(pts
				(xy 0.508 0.2794) (xy 0.508 0.2286) (xy 0.635 0.2286) (xy 0.635 -0.254) (xy 0.5334 -0.254) (xy 0.5334 -0.2794)
				(xy -0.5334 -0.2794) (xy -0.5334 -0.254) (xy -0.635 -0.254) (xy -0.635 0.254) (xy -0.5334 0.254)
				(xy -0.5334 0.2794)
			)
			(stroke
				(width 0)
				(type default)
			)
			(fill no)
			(layer "B.CrtYd")
		)
		(pad "1" smd rect
			(at -0.40005 0 180)
			(size 0.4572 0.508)
			(layers "B.Cu" "B.Mask" "B.Paste")
			(net "T8_NODE2_EN")
		)
		(pad "2" smd rect
			(at 0.40005 0 180)
			(size 0.4572 0.508)
			(layers "B.Cu" "B.Mask" "B.Paste")
			(net "P5V_NODE1")
		)
	)
	(footprint ""
		(layer "B.Cu")
		(at 136.483852 -114.915442 180)
		(property "Reference" "C5"
			(at -0.739902 0.95504 0)
			(unlocked yes)
			(layer "B.SilkS")
			(effects
				(font
					(size 0.7874 0.5842)
					(thickness 0.1524)
				)
				(justify left mirror)
			)
		)
		(property "Value" ""
			(at 0 0 0)
			(layer "B.Fab")
			(effects
				(font
					(size 1.27 1.27)
				)
				(justify mirror)
			)
		)
		(duplicate_pad_numbers_are_jumpers no)
		(fp_line
			(start 0.7874 0.4064)
			(end 0.7874 -0.4064)
			(stroke
				(width 0.1524)
				(type default)
			)
			(layer "B.SilkS")
		)
		(fp_line
			(start 0.7874 -0.4064)
			(end -0.7874 -0.4064)
			(stroke
				(width 0.1524)
				(type default)
			)
			(layer "B.SilkS")
		)
		(fp_line
			(start 0 0.381)
			(end 0 -0.381)
			(stroke
				(width 0.1524)
				(type default)
			)
			(layer "B.SilkS")
		)
		(fp_line
			(start -0.7874 0.4064)
			(end 0.7874 0.4064)
			(stroke
				(width 0.1524)
				(type default)
			)
			(layer "B.SilkS")
		)
		(fp_line
			(start -0.7874 -0.4064)
			(end -0.7874 0.4064)
			(stroke
				(width 0.1524)
				(type default)
			)
			(layer "B.SilkS")
		)
		(fp_poly
			(pts
				(xy 0.5334 0.254) (xy 0.635 0.254) (xy 0.635 0.2286) (xy 0.635 -0.254) (xy 0.5334 -0.254) (xy 0.5334 -0.2794)
				(xy -0.5334 -0.2794) (xy -0.5334 -0.254) (xy -0.635 -0.254) (xy -0.635 0.254) (xy -0.5334 0.254)
				(xy -0.5334 0.2794) (xy 0.508 0.2794) (xy 0.5334 0.2794)
			)
			(stroke
				(width 0)
				(type default)
			)
			(fill no)
			(layer "B.CrtYd")
		)
		(pad "1" smd rect
			(at -0.40005 0)
			(size 0.4572 0.508)
			(layers "B.Cu" "B.Mask" "B.Paste")
			(net "P3V3_CLK_NODE1")
		)
		(pad "2" smd rect
			(at 0.40005 0)
			(size 0.4572 0.508)
			(layers "B.Cu" "B.Mask" "B.Paste")
			(net "GND")
		)
	)
	(footprint ""
		(layer "B.Cu")
		(at 138.684 -46.952154 90)
		(property "Reference" "R1264"
			(at 3.238246 11.93673 270)
			(unlocked yes)
			(layer "B.SilkS")
			(effects
				(font
					(size 0.7874 0.5842)
					(thickness 0.1524)
				)
				(justify left mirror)
			)
		)
		(property "Value" ""
			(at 0 0 90)
			(layer "B.Fab")
			(effects
				(font
					(size 1.27 1.27)
				)
				(justify mirror)
			)
		)
		(duplicate_pad_numbers_are_jumpers no)
		(fp_line
			(start 0.7874 -0.4064)
			(end -0.7874 -0.4064)
			(stroke
				(width 0.1524)
				(type default)
			)
			(layer "B.SilkS")
		)
		(fp_line
			(start -0.7874 -0.4064)
			(end -0.7874 0.4064)
			(stroke
				(width 0.1524)
				(type default)
			)
			(layer "B.SilkS")
		)
		(fp_line
			(start 0.7874 0.4064)
			(end 0.7874 -0.4064)
			(stroke
				(width 0.1524)
				(type default)
			)
			(layer "B.SilkS")
		)
		(fp_line
			(start -0.7874 0.4064)
			(end 0.7874 0.4064)
			(stroke
				(width 0.1524)
				(type default)
			)
			(layer "B.SilkS")
		)
		(fp_poly
			(pts
				(xy 0.508 0.2794) (xy 0.508 0.2286) (xy 0.635 0.2286) (xy 0.635 -0.254) (xy 0.5334 -0.254) (xy 0.5334 -0.2794)
				(xy -0.5334 -0.2794) (xy -0.5334 -0.254) (xy -0.635 -0.254) (xy -0.635 0.254) (xy -0.5334 0.254)
				(xy -0.5334 0.2794)
			)
			(stroke
				(width 0)
				(type default)
			)
			(fill no)
			(layer "B.CrtYd")
		)
		(pad "1" smd rect
			(at -0.40005 0 270)
			(size 0.4572 0.508)
			(layers "B.Cu" "B.Mask" "B.Paste")
			(net "P5V_NODE1")
		)
		(pad "2" smd rect
			(at 0.40005 0 270)
			(size 0.4572 0.508)
			(layers "B.Cu" "B.Mask" "B.Paste")
			(net "UART_DCD_P3_N")
		)
	)
	(footprint ""
		(layer "B.Cu")
		(at 156.77769 -173.809914 -90)
		(property "Reference" "C917"
			(at 1.045972 -1.034288 270)
			(unlocked yes)
			(layer "B.SilkS")
			(effects
				(font
					(size 0.7874 0.5842)
					(thickness 0.1524)
				)
				(justify left mirror)
			)
		)
		(property "Value" ""
			(at 0 0 90)
			(layer "B.Fab")
			(effects
				(font
					(size 1.27 1.27)
				)
				(justify mirror)
			)
		)
		(duplicate_pad_numbers_are_jumpers no)
		(fp_line
			(start -0.7874 0.4064)
			(end 0.7874 0.4064)
			(stroke
				(width 0.1524)
				(type default)
			)
			(layer "B.SilkS")
		)
		(fp_line
			(start 0.7874 0.4064)
			(end 0.7874 -0.4064)
			(stroke
				(width 0.1524)
				(type default)
			)
			(layer "B.SilkS")
		)
		(fp_line
			(start 0 0.381)
			(end 0 -0.381)
			(stroke
				(width 0.1524)
				(type default)
			)
			(layer "B.SilkS")
		)
		(fp_line
			(start -0.7874 -0.4064)
			(end -0.7874 0.4064)
			(stroke
				(width 0.1524)
				(type default)
			)
			(layer "B.SilkS")
		)
		(fp_line
			(start 0.7874 -0.4064)
			(end -0.7874 -0.4064)
			(stroke
				(width 0.1524)
				(type default)
			)
			(layer "B.SilkS")
		)
		(fp_poly
			(pts
				(xy 0.5334 0.254) (xy 0.635 0.254) (xy 0.635 0.2286) (xy 0.635 -0.254) (xy 0.5334 -0.254) (xy 0.5334 -0.2794)
				(xy -0.5334 -0.2794) (xy -0.5334 -0.254) (xy -0.635 -0.254) (xy -0.635 0.254) (xy -0.5334 0.254)
				(xy -0.5334 0.2794) (xy 0.508 0.2794) (xy 0.5334 0.2794)
			)
			(stroke
				(width 0)
				(type default)
			)
			(fill no)
			(layer "B.CrtYd")
		)
		(pad "1" smd rect
			(at -0.40005 0 90)
			(size 0.4572 0.508)
			(layers "B.Cu" "B.Mask" "B.Paste")
			(net "GND")
		)
		(pad "2" smd rect
			(at 0.40005 0 90)
			(size 0.4572 0.508)
			(layers "B.Cu" "B.Mask" "B.Paste")
			(net "N54365837")
		)
	)
)
